(kicad_pcb
	(version 20260206)
	(generator "pcbnew")
	(generator_version "10.0")
	(general
		(thickness 1.6)
		(legacy_teardrops no)
	)
	(paper "A4")
	(title_block
		(title "Bryce Canyon_R.DPB_16317-1_OCP.brd")
		(comment 1 "Bryce Canyon / footprints 1239-1246 of 2099")
	)
	(layers
		(0 "F.Cu" signal "TOP")
		(4 "In1.Cu" signal "L2GND")
		(6 "In2.Cu" signal "L3")
		(8 "In3.Cu" signal "L4VCC")
		(10 "In4.Cu" signal "L5VCC")
		(12 "In5.Cu" signal "L6")
		(14 "In6.Cu" signal "L7GND")
		(2 "B.Cu" signal "BOTTOM")
		(9 "F.Adhes" user "F.Adhesive")
		(11 "B.Adhes" user "B.Adhesive")
		(13 "F.Paste" user "Package Geometry/Pastemask Top")
		(15 "B.Paste" user "Package Geometry/Pastemask Bottom")
		(5 "F.SilkS" user "Ref Des/Silkscreen Top")
		(7 "B.SilkS" user "Ref Des/Silkscreen Bottom")
		(1 "F.Mask" user "Board Geometry/Soldermask Top")
		(3 "B.Mask" user "Board Geometry/Soldermask Bottom")
		(17 "Dwgs.User" user "User.Drawings")
		(19 "Cmts.User" user "User.Comments")
		(21 "Eco1.User" user "User.Eco1")
		(23 "Eco2.User" user "User.Eco2")
		(25 "Edge.Cuts" user "Board Geometry/Outline")
		(27 "Margin" user)
		(31 "F.CrtYd" user "Package Geometry/Place Bound Top")
		(29 "B.CrtYd" user "Package Geometry/Place Bound Bottom")
		(35 "F.Fab" user "Ref Des/Assembly Top")
		(33 "B.Fab" user "Ref Des/Assembly Bottom")
	)
	(footprint ""
		(layer "F.Cu")
		(at 457.7842 -135.6614 -90)
		(property "Reference" "C324"
			(at 0 0 270)
			(layer "F.SilkS")
			(hide yes)
			(effects
				(font
					(size 1.27 1.27)
				)
			)
		)
		(property "Value" "SCD033U25V2KX-GP"
			(at 1.1811 -2.7051 270)
			(unlocked yes)
			(layer "F.Fab")
			(hide yes)
			(effects
				(font
					(size 1.016 1.016)
					(thickness 0.1524)
				)
			)
		)
		(property "Device Type" "C402H22"
			(at 1.1811 -4.2291 270)
			(unlocked yes)
			(layer "F.Fab")
			(hide yes)
			(effects
				(font
					(size 1.016 1.016)
					(thickness 0.1524)
				)
			)
		)
		(duplicate_pad_numbers_are_jumpers no)
		(fp_rect
			(start -0.4318 0.9525)
			(end 0.4318 -0.9525)
			(stroke
				(width 0)
				(type default)
			)
			(fill no)
			(layer "F.CrtYd")
		)
		(fp_rect
			(start -0.4318 0.9525)
			(end 0.4318 -0.9525)
			(stroke
				(width 0)
				(type default)
			)
			(fill no)
			(layer "F.Fab")
		)
		(pad "1" smd custom
			(at 0 -0.4445 270)
			(size 0.1524 0.1524)
			(layers "F.Cu" "F.Mask" "F.Paste")
			(net "SW_HDD_P22")
			(options
				(clearance outline)
				(anchor circle)
			)
			(primitives
				(gr_poly
					(pts
						(arc
							(start 0.3048 -0.2032)
							(mid 0.275042 -0.275042)
							(end 0.2032 -0.3048)
						)
						(arc
							(start -0.2032 -0.3048)
							(mid -0.275042 -0.275042)
							(end -0.3048 -0.2032)
						)
						(arc
							(start -0.3048 0.2032)
							(mid -0.275042 0.275042)
							(end -0.2032 0.3048)
						)
						(arc
							(start 0.2032 0.3048)
							(mid 0.275042 0.275042)
							(end 0.3048 0.2032)
						)
					)
					(width 0)
					(fill yes)
				)
			)
		)
		(pad "2" smd custom
			(at 0 0.4445 270)
			(size 0.1524 0.1524)
			(layers "F.Cu" "F.Mask" "F.Paste")
			(net "GND")
			(options
				(clearance outline)
				(anchor circle)
			)
			(primitives
				(gr_poly
					(pts
						(arc
							(start 0.3048 -0.2032)
							(mid 0.275042 -0.275042)
							(end 0.2032 -0.3048)
						)
						(arc
							(start -0.2032 -0.3048)
							(mid -0.275042 -0.275042)
							(end -0.3048 -0.2032)
						)
						(arc
							(start -0.3048 0.2032)
							(mid -0.275042 0.275042)
							(end -0.2032 0.3048)
						)
						(arc
							(start 0.2032 0.3048)
							(mid 0.275042 0.275042)
							(end 0.3048 0.2032)
						)
					)
					(width 0)
					(fill yes)
				)
			)
		)
	)
	(footprint ""
		(layer "F.Cu")
		(at 109.347 -265.684 -90)
		(property "Reference" "C73"
			(at 0 0 270)
			(layer "F.SilkS")
			(hide yes)
			(effects
				(font
					(size 1.27 1.27)
				)
			)
		)
		(property "Value" "SC4D7U25V5KX-1-GP"
			(at -0.0762 -6.1214 270)
			(unlocked yes)
			(layer "F.Fab")
			(hide yes)
			(effects
				(font
					(size 1.016 1.016)
					(thickness 0.1524)
				)
			)
		)
		(property "Device Type" "C805H58"
			(at -0.0762 -8.1534 270)
			(unlocked yes)
			(layer "F.Fab")
			(hide yes)
			(effects
				(font
					(size 1.016 1.016)
					(thickness 0.1524)
				)
			)
		)
		(duplicate_pad_numbers_are_jumpers no)
		(fp_line
			(start 0.635 0)
			(end -0.635 0)
			(stroke
				(width 0.508)
				(type default)
			)
			(layer "F.SilkS")
		)
		(fp_rect
			(start -0.9652 1.778)
			(end 0.9652 -1.778)
			(stroke
				(width 0)
				(type default)
			)
			(fill no)
			(layer "F.CrtYd")
		)
		(fp_poly
			(pts
				(xy -0.9652 -1.778) (xy 0.9652 -1.778) (xy 0.9652 1.778) (xy -0.9652 1.778)
			)
			(stroke
				(width 0)
				(type default)
			)
			(fill no)
			(layer "F.Fab")
		)
		(pad "1" smd rect
			(at 0 -0.9652 270)
			(size 1.397 1.143)
			(layers "F.Cu" "F.Mask" "F.Paste")
			(net "P12V_HDD3")
		)
		(pad "2" smd rect
			(at 0 0.9652 270)
			(size 1.397 1.143)
			(layers "F.Cu" "F.Mask" "F.Paste")
			(net "GND")
		)
	)
	(footprint ""
		(layer "F.Cu")
		(at 16.764 -24.13 -90)
		(property "Reference" "C350"
			(at 0 0 270)
			(layer "F.SilkS")
			(hide yes)
			(effects
				(font
					(size 1.27 1.27)
				)
			)
		)
		(property "Value" "SCD033U25V2KX-GP"
			(at 1.1811 -2.7051 270)
			(unlocked yes)
			(layer "F.Fab")
			(hide yes)
			(effects
				(font
					(size 1.016 1.016)
					(thickness 0.1524)
				)
			)
		)
		(property "Device Type" "C402H22"
			(at 1.1811 -4.2291 270)
			(unlocked yes)
			(layer "F.Fab")
			(hide yes)
			(effects
				(font
					(size 1.016 1.016)
					(thickness 0.1524)
				)
			)
		)
		(duplicate_pad_numbers_are_jumpers no)
		(fp_rect
			(start -0.4318 0.9525)
			(end 0.4318 -0.9525)
			(stroke
				(width 0)
				(type default)
			)
			(fill no)
			(layer "F.CrtYd")
		)
		(fp_rect
			(start -0.4318 0.9525)
			(end 0.4318 -0.9525)
			(stroke
				(width 0)
				(type default)
			)
			(fill no)
			(layer "F.Fab")
		)
		(pad "1" smd custom
			(at 0 -0.4445 270)
			(size 0.1524 0.1524)
			(layers "F.Cu" "F.Mask" "F.Paste")
			(net "SW_HDD_P24")
			(options
				(clearance outline)
				(anchor circle)
			)
			(primitives
				(gr_poly
					(pts
						(arc
							(start 0.3048 -0.2032)
							(mid 0.275042 -0.275042)
							(end 0.2032 -0.3048)
						)
						(arc
							(start -0.2032 -0.3048)
							(mid -0.275042 -0.275042)
							(end -0.3048 -0.2032)
						)
						(arc
							(start -0.3048 0.2032)
							(mid -0.275042 0.275042)
							(end -0.2032 0.3048)
						)
						(arc
							(start 0.2032 0.3048)
							(mid 0.275042 0.275042)
							(end 0.3048 0.2032)
						)
					)
					(width 0)
					(fill yes)
				)
			)
		)
		(pad "2" smd custom
			(at 0 0.4445 270)
			(size 0.1524 0.1524)
			(layers "F.Cu" "F.Mask" "F.Paste")
			(net "GND")
			(options
				(clearance outline)
				(anchor circle)
			)
			(primitives
				(gr_poly
					(pts
						(arc
							(start 0.3048 -0.2032)
							(mid 0.275042 -0.275042)
							(end 0.2032 -0.3048)
						)
						(arc
							(start -0.2032 -0.3048)
							(mid -0.275042 -0.275042)
							(end -0.3048 -0.2032)
						)
						(arc
							(start -0.3048 0.2032)
							(mid -0.275042 0.275042)
							(end -0.2032 0.3048)
						)
						(arc
							(start 0.2032 0.3048)
							(mid 0.275042 0.275042)
							(end 0.3048 0.2032)
						)
					)
					(width 0)
					(fill yes)
				)
			)
		)
	)
	(footprint ""
		(layer "F.Cu")
		(at 414.436052 -128.627124 180)
		(property "Reference" "VIA43"
			(at 0 0 180)
			(layer "F.SilkS")
			(hide yes)
			(effects
				(font
					(size 1.27 1.27)
				)
			)
		)
		(property "Value" "100OHM-8L-2D36MM-L18-GP"
			(at 3.8989 0.5715 180)
			(unlocked yes)
			(layer "F.Fab")
			(hide yes)
			(effects
				(font
					(size 1.016 1.016)
					(thickness 0.1524)
				)
			)
		)
		(property "Device Type" "VIA-PCIE-4P-414097"
			(at 3.8989 -0.9525 180)
			(unlocked yes)
			(layer "F.Fab")
			(hide yes)
			(effects
				(font
					(size 1.016 1.016)
					(thickness 0.1524)
				)
			)
		)
		(duplicate_pad_numbers_are_jumpers no)
		(fp_rect
			(start -2.0701 0.4826)
			(end 2.0701 -0.4826)
			(stroke
				(width 0)
				(type default)
			)
			(fill no)
			(layer "F.CrtYd")
		)
		(fp_rect
			(start -2.0701 0.4826)
			(end 2.0701 -0.4826)
			(stroke
				(width 0)
				(type default)
			)
			(fill no)
			(layer "F.Fab")
		)
		(pad "1" thru_hole circle
			(at -1.5875 0 180)
			(size 0.508 0.508)
			(drill 0.254)
			(layers "*.Cu" "*.Mask")
			(remove_unused_layers no)
			(net "GND")
			(clearance 0.2286)
			(thermal_gap 0.2286)
		)
		(pad "2" thru_hole circle
			(at -0.5715 0 180)
			(size 0.508 0.508)
			(drill 0.254)
			(layers "*.Cu" "*.Mask")
			(remove_unused_layers no)
			(net "PHY_SCC_B_TO_DRV_B_21_DP")
			(clearance 0.2286)
			(thermal_gap 0.2286)
		)
		(pad "3" thru_hole circle
			(at 0.5715 0 180)
			(size 0.508 0.508)
			(drill 0.254)
			(layers "*.Cu" "*.Mask")
			(remove_unused_layers no)
			(net "PHY_SCC_B_TO_DRV_B_21_DN")
			(clearance 0.2286)
			(thermal_gap 0.2286)
		)
		(pad "4" thru_hole circle
			(at 1.5875 0 180)
			(size 0.508 0.508)
			(drill 0.254)
			(layers "*.Cu" "*.Mask")
			(remove_unused_layers no)
			(net "GND")
			(clearance 0.2286)
			(thermal_gap 0.2286)
		)
	)
	(footprint ""
		(layer "F.Cu")
		(at 445.9859 -128.627124 180)
		(property "Reference" "VIA45"
			(at 0 0 180)
			(layer "F.SilkS")
			(hide yes)
			(effects
				(font
					(size 1.27 1.27)
				)
			)
		)
		(property "Value" "100OHM-8L-2D36MM-L18-GP"
			(at 3.8989 0.5715 180)
			(unlocked yes)
			(layer "F.Fab")
			(hide yes)
			(effects
				(font
					(size 1.016 1.016)
					(thickness 0.1524)
				)
			)
		)
		(property "Device Type" "VIA-PCIE-4P-414097"
			(at 3.8989 -0.9525 180)
			(unlocked yes)
			(layer "F.Fab")
			(hide yes)
			(effects
				(font
					(size 1.016 1.016)
					(thickness 0.1524)
				)
			)
		)
		(duplicate_pad_numbers_are_jumpers no)
		(fp_rect
			(start -2.0701 0.4826)
			(end 2.0701 -0.4826)
			(stroke
				(width 0)
				(type default)
			)
			(fill no)
			(layer "F.CrtYd")
		)
		(fp_rect
			(start -2.0701 0.4826)
			(end 2.0701 -0.4826)
			(stroke
				(width 0)
				(type default)
			)
			(fill no)
			(layer "F.Fab")
		)
		(pad "1" thru_hole circle
			(at -1.5875 0 180)
			(size 0.508 0.508)
			(drill 0.254)
			(layers "*.Cu" "*.Mask")
			(remove_unused_layers no)
			(net "GND")
			(clearance 0.2286)
			(thermal_gap 0.2286)
		)
		(pad "2" thru_hole circle
			(at -0.5715 0 180)
			(size 0.508 0.508)
			(drill 0.254)
			(layers "*.Cu" "*.Mask")
			(remove_unused_layers no)
			(net "PHY_SCC_B_TO_DRV_B_22_DP")
			(clearance 0.2286)
			(thermal_gap 0.2286)
		)
		(pad "3" thru_hole circle
			(at 0.5715 0 180)
			(size 0.508 0.508)
			(drill 0.254)
			(layers "*.Cu" "*.Mask")
			(remove_unused_layers no)
			(net "PHY_SCC_B_TO_DRV_B_22_DN")
			(clearance 0.2286)
			(thermal_gap 0.2286)
		)
		(pad "4" thru_hole circle
			(at 1.5875 0 180)
			(size 0.508 0.508)
			(drill 0.254)
			(layers "*.Cu" "*.Mask")
			(remove_unused_layers no)
			(net "GND")
			(clearance 0.2286)
			(thermal_gap 0.2286)
		)
	)
	(footprint ""
		(layer "F.Cu")
		(at 284.955742 -379.335792 90)
		(property "Reference" "R1065"
			(at 0 0 90)
			(layer "F.SilkS")
			(hide yes)
			(effects
				(font
					(size 1.27 1.27)
				)
			)
		)
		(property "Value" "68R5J-GP"
			(at 0 -8.9535 90)
			(unlocked yes)
			(layer "F.Fab")
			(hide yes)
			(effects
				(font
					(size 1.27 1.016)
					(thickness 0.1524)
				)
			)
		)
		(property "Device Type" "R805H24"
			(at 0 -10.6299 90)
			(unlocked yes)
			(layer "F.Fab")
			(hide yes)
			(effects
				(font
					(size 1.27 1.016)
					(thickness 0.1524)
				)
			)
		)
		(duplicate_pad_numbers_are_jumpers no)
		(fp_line
			(start 0.889 -1.7018)
			(end -0.889 -1.7018)
			(stroke
				(width 0.1524)
				(type default)
			)
			(layer "F.SilkS")
		)
		(fp_line
			(start 0.889 -1.7018)
			(end 0.889 -0.381)
			(stroke
				(width 0.1524)
				(type default)
			)
			(layer "F.SilkS")
		)
		(fp_line
			(start -0.889 -1.7018)
			(end -0.889 0.2794)
			(stroke
				(width 0.1524)
				(type default)
			)
			(layer "F.SilkS")
		)
		(fp_line
			(start -0.889 0.0762)
			(end -0.889 1.7018)
			(stroke
				(width 0.1524)
				(type default)
			)
			(layer "F.SilkS")
		)
		(fp_line
			(start 0.889 1.7018)
			(end 0.889 -0.508)
			(stroke
				(width 0.1524)
				(type default)
			)
			(layer "F.SilkS")
		)
		(fp_line
			(start -0.889 1.7018)
			(end 0.889 1.7018)
			(stroke
				(width 0.1524)
				(type default)
			)
			(layer "F.SilkS")
		)
		(fp_poly
			(pts
				(xy 0.9652 -1.778) (xy 0.9652 1.778) (xy -0.9652 1.778) (xy -0.9652 -1.778)
			)
			(stroke
				(width 0)
				(type default)
			)
			(fill no)
			(layer "F.CrtYd")
		)
		(fp_rect
			(start -0.9652 1.778)
			(end 0.9652 -1.778)
			(stroke
				(width 0)
				(type default)
			)
			(fill no)
			(layer "F.Fab")
		)
		(pad "1" smd rect
			(at 0 -0.9652 90)
			(size 1.397 1.143)
			(layers "F.Cu" "F.Mask" "F.Paste")
			(net "EMITTER_K")
		)
		(pad "2" smd rect
			(at 0 0.9652 90)
			(size 1.397 1.143)
			(layers "F.Cu" "F.Mask" "F.Paste")
			(net "GND")
		)
	)
	(footprint ""
		(layer "F.Cu")
		(at 343.454228 -99.756976 180)
		(property "Reference" "Q238"
			(at 0 0 180)
			(layer "F.SilkS")
			(hide yes)
			(effects
				(font
					(size 1.27 1.27)
				)
			)
		)
		(property "Value" "2N7002K-2-GP"
			(at 0.127 -8.9662 180)
			(unlocked yes)
			(layer "F.Fab")
			(hide yes)
			(effects
				(font
					(size 1.016 1.016)
					(thickness 0.1524)
				)
			)
		)
		(property "Device Type" "SOT23DGS2D4H44"
			(at 0.127 -10.4902 180)
			(unlocked yes)
			(layer "F.Fab")
			(hide yes)
			(effects
				(font
					(size 1.016 1.016)
					(thickness 0.1524)
				)
			)
		)
		(duplicate_pad_numbers_are_jumpers no)
		(fp_line
			(start 1.651 1.778)
			(end 1.651 -1.778)
			(stroke
				(width 0.1524)
				(type default)
			)
			(layer "F.SilkS")
		)
		(fp_line
			(start 1.651 -1.778)
			(end -1.651 -1.778)
			(stroke
				(width 0.1524)
				(type default)
			)
			(layer "F.SilkS")
		)
		(fp_line
			(start -1.651 1.778)
			(end 1.651 1.778)
			(stroke
				(width 0.1524)
				(type default)
			)
			(layer "F.SilkS")
		)
		(fp_line
			(start -1.651 -1.778)
			(end -1.651 1.778)
			(stroke
				(width 0.1524)
				(type default)
			)
			(layer "F.SilkS")
		)
		(fp_poly
			(pts
				(xy -1.778 1.8796) (xy -1.778 -1.8796) (xy 1.778 -1.8796) (xy 1.778 1.8796)
			)
			(stroke
				(width 0)
				(type default)
			)
			(fill no)
			(layer "F.CrtYd")
		)
		(fp_poly
			(pts
				(xy -1.778 1.8796) (xy -1.778 -1.8796) (xy 1.778 -1.8796) (xy 1.778 1.8796)
			)
			(stroke
				(width 0)
				(type default)
			)
			(fill no)
			(layer "F.Fab")
		)
		(pad "D" smd custom
			(at 0 -0.9525 180)
			(size 0.1905 0.1905)
			(layers "F.Cu" "F.Mask" "F.Paste")
			(net "FLT_HDD19_N")
			(options
				(clearance outline)
				(anchor circle)
			)
			(primitives
				(gr_poly
					(pts
						(arc
							(start -0.1778 0.5715)
							(mid -0.321484 0.511984)
							(end -0.381 0.3683)
						)
						(arc
							(start -0.381 -0.3683)
							(mid -0.321484 -0.511984)
							(end -0.1778 -0.5715)
						)
						(arc
							(start 0.1778 -0.5715)
							(mid 0.321484 -0.511984)
							(end 0.381 -0.3683)
						)
						(arc
							(start 0.381 0.3683)
							(mid 0.321484 0.511984)
							(end 0.1778 0.5715)
						)
					)
					(width 0)
					(fill yes)
				)
			)
		)
		(pad "G" smd custom
			(at -0.98425 0.9525 180)
			(size 0.1905 0.1905)
			(layers "F.Cu" "F.Mask" "F.Paste")
			(net "DRIVE_B_19_FLT_LED")
			(options
				(clearance outline)
				(anchor circle)
			)
			(primitives
				(gr_poly
					(pts
						(arc
							(start -0.1778 0.5715)
							(mid -0.321484 0.511984)
							(end -0.381 0.3683)
						)
						(arc
							(start -0.381 -0.3683)
							(mid -0.321484 -0.511984)
							(end -0.1778 -0.5715)
						)
						(arc
							(start 0.1778 -0.5715)
							(mid 0.321484 -0.511984)
							(end 0.381 -0.3683)
						)
						(arc
							(start 0.381 0.3683)
							(mid 0.321484 0.511984)
							(end 0.1778 0.5715)
						)
					)
					(width 0)
					(fill yes)
				)
			)
		)
		(pad "S" smd custom
			(at 0.98425 0.9525 180)
			(size 0.1905 0.1905)
			(layers "F.Cu" "F.Mask" "F.Paste")
			(net "GND")
			(options
				(clearance outline)
				(anchor circle)
			)
			(primitives
				(gr_poly
					(pts
						(arc
							(start -0.1778 0.5715)
							(mid -0.321484 0.511984)
							(end -0.381 0.3683)
						)
						(arc
							(start -0.381 -0.3683)
							(mid -0.321484 -0.511984)
							(end -0.1778 -0.5715)
						)
						(arc
							(start 0.1778 -0.5715)
							(mid 0.321484 -0.511984)
							(end 0.381 -0.3683)
						)
						(arc
							(start 0.381 0.3683)
							(mid 0.321484 0.511984)
							(end 0.1778 0.5715)
						)
					)
					(width 0)
					(fill yes)
				)
			)
		)
	)
	(footprint ""
		(layer "F.Cu")
		(at 409.194 -99.187)
		(property "Reference" "R448"
			(at 0 0 0)
			(layer "F.SilkS")
			(hide yes)
			(effects
				(font
					(size 1.27 1.27)
				)
			)
		)
		(property "Value" "130R3F-GP"
			(at -0.0254 -2.5146 0)
			(unlocked yes)
			(layer "F.Fab")
			(hide yes)
			(effects
				(font
					(size 1.016 1.016)
					(thickness 0.1524)
				)
			)
		)
		(property "Device Type" "R603H22"
			(at -0.0254 -4.0386 0)
			(unlocked yes)
			(layer "F.Fab")
			(hide yes)
			(effects
				(font
					(size 1.016 1.016)
					(thickness 0.1524)
				)
			)
		)
		(duplicate_pad_numbers_are_jumpers no)
		(fp_line
			(start -0.4826 0)
			(end -0.2032 0)
			(stroke
				(width 0.2032)
				(type default)
			)
			(layer "F.SilkS")
		)
		(fp_line
			(start 0.2032 0)
			(end 0.4826 0)
			(stroke
				(width 0.2032)
				(type default)
			)
			(layer "F.SilkS")
		)
		(fp_rect
			(start -0.5842 1.3335)
			(end 0.5842 -1.3335)
			(stroke
				(width 0)
				(type default)
			)
			(fill no)
			(layer "F.CrtYd")
		)
		(fp_rect
			(start -0.5842 1.3335)
			(end 0.5842 -1.3335)
			(stroke
				(width 0)
				(type default)
			)
			(fill no)
			(layer "F.Fab")
		)
		(pad "1" smd custom
			(at 0 -0.762)
			(size 0.2159 0.2159)
			(layers "F.Cu" "F.Mask" "F.Paste")
			(net "P5V_B_4")
			(options
				(clearance outline)
				(anchor circle)
			)
			(primitives
				(gr_poly
					(pts
						(arc
							(start -0.3302 -0.4318)
							(mid -0.402042 -0.402042)
							(end -0.4318 -0.3302)
						)
						(arc
							(start -0.4318 0.3302)
							(mid -0.402042 0.402042)
							(end -0.3302 0.4318)
						)
						(arc
							(start 0.3302 0.4318)
							(mid 0.402042 0.402042)
							(end 0.4318 0.3302)
						)
						(arc
							(start 0.4318 -0.3302)
							(mid 0.402042 -0.402042)
							(end 0.3302 -0.4318)
						)
					)
					(width 0)
					(fill yes)
				)
			)
		)
		(pad "2" smd custom
			(at 0 0.762)
			(size 0.2159 0.2159)
			(layers "F.Cu" "F.Mask" "F.Paste")
			(net "FLT_HDD21")
			(options
				(clearance outline)
				(anchor circle)
			)
			(primitives
				(gr_poly
					(pts
						(arc
							(start -0.3302 -0.4318)
							(mid -0.402042 -0.402042)
							(end -0.4318 -0.3302)
						)
						(arc
							(start -0.4318 0.3302)
							(mid -0.402042 0.402042)
							(end -0.3302 0.4318)
						)
						(arc
							(start 0.3302 0.4318)
							(mid 0.402042 0.402042)
							(end 0.4318 0.3302)
						)
						(arc
							(start 0.4318 -0.3302)
							(mid 0.402042 -0.402042)
							(end 0.3302 -0.4318)
						)
					)
					(width 0)
					(fill yes)
				)
			)
		)
	)
)
